# S9S_MB_2U (Grand Teton) — schematic netlist excerpt (pin names and nets, part order shuffled) for the footprints in the layout excerpt that follows; sources: Cadence DE-HDL packaged netlist, KiCad conversion of 03242023_DA0F0TMBIJ0_F0T_Motherboard_J_brd_V01_OCP.brd

H128  HOLE  EMPTY  pkg TH  page 311 : \1\ = GND
C428  Q_CAP  22UF 4V 20% X6S  pkg C0402  page 77 : A = PVCCFA_EHV_FIVRA_CPU1 ; B = GND
PC336  Q_CAP  470PF 50V 10% X7R  pkg 0402  page 266 : A = PVCCIN_CPU0_ATSEN ; B = GND

(kicad_pcb
	(version 20260206)
	(generator "pcbnew")
	(generator_version "10.0")
	(general
		(thickness 1.6)
		(legacy_teardrops no)
	)
	(paper "A4")
	(title_block
		(title "03242023_DA0F0TMBIJ0_F0T_Motherboard_J_brd_V01_OCP.brd")
		(comment 1 "Grand Teton / footprints 29-31 of 6105")
	)
	(layers
		(0 "F.Cu" signal "TOP")
		(4 "In1.Cu" signal "GND")
		(6 "In2.Cu" signal "IN1")
		(8 "In3.Cu" signal "GND1")
		(10 "In4.Cu" signal "IN2")
		(12 "In5.Cu" signal "GND2")
		(14 "In6.Cu" signal "IN3")
		(16 "In7.Cu" signal "GND3")
		(18 "In8.Cu" signal "VCC")
		(20 "In9.Cu" signal "VCC1")
		(22 "In10.Cu" signal "GND4")
		(24 "In11.Cu" signal "IN4")
		(26 "In12.Cu" signal "GND5")
		(28 "In13.Cu" signal "IN5")
		(30 "In14.Cu" signal "GND6")
		(32 "In15.Cu" signal "IN6")
		(34 "In16.Cu" signal "GND7")
		(2 "B.Cu" signal "BOTTOM")
		(9 "F.Adhes" user "F.Adhesive")
		(11 "B.Adhes" user "B.Adhesive")
		(13 "F.Paste" user "Package Geometry/Pastemask Top")
		(15 "B.Paste" user "Package Geometry/Pastemask Bottom")
		(5 "F.SilkS" user "Ref Des/Silkscreen Top")
		(7 "B.SilkS" user "Ref Des/Silkscreen Bottom")
		(1 "F.Mask" user "Board Geometry/Soldermask Top")
		(3 "B.Mask" user "Board Geometry/Soldermask Bottom")
		(17 "Dwgs.User" user "User.Drawings")
		(19 "Cmts.User" user "User.Comments")
		(21 "Eco1.User" user "User.Eco1")
		(23 "Eco2.User" user "User.Eco2")
		(25 "Edge.Cuts" user "Board Geometry/Outline")
		(27 "Margin" user)
		(31 "F.CrtYd" user "Package Geometry/Place Bound Top")
		(29 "B.CrtYd" user "Package Geometry/Place Bound Bottom")
		(35 "F.Fab" user "Ref Des/Assembly Top")
		(33 "B.Fab" user "Ref Des/Assembly Bottom")
	)
	(footprint ""
		(layer "F.Cu")
		(at 104.347264 -260.36524 -90)
		(property "Reference" "C428"
			(at 0 0 270)
			(layer "F.SilkS")
			(hide yes)
			(effects
				(font
					(size 1.27 1.27)
				)
			)
		)
		(property "Value" ""
			(at 0 0 270)
			(layer "F.Fab")
			(effects
				(font
					(size 1.27 1.27)
				)
			)
		)
		(duplicate_pad_numbers_are_jumpers no)
		(fp_line
			(start -0.7874 0.4064)
			(end -0.7874 -0.4064)
			(stroke
				(width 0.1524)
				(type default)
			)
			(layer "F.SilkS")
		)
		(fp_line
			(start 0.7874 0.4064)
			(end -0.7874 0.4064)
			(stroke
				(width 0.1524)
				(type default)
			)
			(layer "F.SilkS")
		)
		(fp_line
			(start -0.7874 -0.4064)
			(end 0.7874 -0.4064)
			(stroke
				(width 0.1524)
				(type default)
			)
			(layer "F.SilkS")
		)
		(fp_line
			(start 0.7874 -0.4064)
			(end 0.7874 0.4064)
			(stroke
				(width 0.1524)
				(type default)
			)
			(layer "F.SilkS")
		)
		(fp_line
			(start -0.67945 0.3048)
			(end -0.67945 -0.305054)
			(stroke
				(width 0.1)
				(type default)
			)
			(layer "F.Fab")
		)
		(fp_line
			(start -0.12065 0.3048)
			(end -0.67945 0.3048)
			(stroke
				(width 0.1)
				(type default)
			)
			(layer "F.Fab")
		)
		(fp_line
			(start 0.120396 0.3048)
			(end 0.120396 0.2794)
			(stroke
				(width 0.1)
				(type default)
			)
			(layer "F.Fab")
		)
		(fp_line
			(start 0.67945 0.3048)
			(end 0.120396 0.3048)
			(stroke
				(width 0.1)
				(type default)
			)
			(layer "F.Fab")
		)
		(fp_line
			(start -0.12065 0.2794)
			(end -0.12065 0.3048)
			(stroke
				(width 0.1)
				(type default)
			)
			(layer "F.Fab")
		)
		(fp_line
			(start 0.120396 0.2794)
			(end -0.12065 0.2794)
			(stroke
				(width 0.1)
				(type default)
			)
			(layer "F.Fab")
		)
		(fp_line
			(start -0.12065 -0.2794)
			(end 0.12065 -0.2794)
			(stroke
				(width 0.1)
				(type default)
			)
			(layer "F.Fab")
		)
		(fp_line
			(start 0.12065 -0.2794)
			(end 0.12065 -0.3048)
			(stroke
				(width 0.1)
				(type default)
			)
			(layer "F.Fab")
		)
		(fp_line
			(start 0.12065 -0.3048)
			(end 0.67945 -0.3048)
			(stroke
				(width 0.1)
				(type default)
			)
			(layer "F.Fab")
		)
		(fp_line
			(start 0.67945 -0.3048)
			(end 0.67945 0.3048)
			(stroke
				(width 0.1)
				(type default)
			)
			(layer "F.Fab")
		)
		(fp_line
			(start -0.67945 -0.305054)
			(end -0.12065 -0.305054)
			(stroke
				(width 0.1)
				(type default)
			)
			(layer "F.Fab")
		)
		(fp_line
			(start -0.12065 -0.305054)
			(end -0.12065 -0.2794)
			(stroke
				(width 0.1)
				(type default)
			)
			(layer "F.Fab")
		)
		(pad "1" smd circle
			(at -0.40005 0 270)
			(size 0 0)
			(layers "F.Cu" "F.Mask" "F.Paste")
			(net "PVCCFA_EHV_FIVRA_CPU1")
		)
		(pad "2" smd circle
			(at 0.40005 0 270)
			(size 0 0)
			(layers "F.Cu" "F.Mask" "F.Paste")
			(net "GND")
		)
	)
	(footprint ""
		(layer "F.Cu")
		(at 362.646468 -357.91775)
		(property "Reference" "PC336"
			(at 0 0 0)
			(layer "F.SilkS")
			(hide yes)
			(effects
				(font
					(size 1.27 1.27)
				)
			)
		)
		(property "Value" ""
			(at 0 0 0)
			(layer "F.Fab")
			(effects
				(font
					(size 1.27 1.27)
				)
			)
		)
		(duplicate_pad_numbers_are_jumpers no)
		(fp_line
			(start -0.7874 -0.4064)
			(end 0.7874 -0.4064)
			(stroke
				(width 0.1524)
				(type default)
			)
			(layer "F.SilkS")
		)
		(fp_line
			(start -0.7874 0.4064)
			(end -0.7874 -0.4064)
			(stroke
				(width 0.1524)
				(type default)
			)
			(layer "F.SilkS")
		)
		(fp_line
			(start 0.7874 -0.4064)
			(end 0.7874 0.4064)
			(stroke
				(width 0.1524)
				(type default)
			)
			(layer "F.SilkS")
		)
		(fp_line
			(start 0.7874 0.4064)
			(end -0.7874 0.4064)
			(stroke
				(width 0.1524)
				(type default)
			)
			(layer "F.SilkS")
		)
		(fp_line
			(start -0.67945 -0.305054)
			(end -0.12065 -0.305054)
			(stroke
				(width 0.1)
				(type default)
			)
			(layer "F.Fab")
		)
		(fp_line
			(start -0.67945 0.3048)
			(end -0.67945 -0.305054)
			(stroke
				(width 0.1)
				(type default)
			)
			(layer "F.Fab")
		)
		(fp_line
			(start -0.12065 -0.305054)
			(end -0.12065 -0.2794)
			(stroke
				(width 0.1)
				(type default)
			)
			(layer "F.Fab")
		)
		(fp_line
			(start -0.12065 -0.2794)
			(end 0.12065 -0.2794)
			(stroke
				(width 0.1)
				(type default)
			)
			(layer "F.Fab")
		)
		(fp_line
			(start -0.12065 0.2794)
			(end -0.12065 0.3048)
			(stroke
				(width 0.1)
				(type default)
			)
			(layer "F.Fab")
		)
		(fp_line
			(start -0.12065 0.3048)
			(end -0.67945 0.3048)
			(stroke
				(width 0.1)
				(type default)
			)
			(layer "F.Fab")
		)
		(fp_line
			(start 0.120396 0.2794)
			(end -0.12065 0.2794)
			(stroke
				(width 0.1)
				(type default)
			)
			(layer "F.Fab")
		)
		(fp_line
			(start 0.120396 0.3048)
			(end 0.120396 0.2794)
			(stroke
				(width 0.1)
				(type default)
			)
			(layer "F.Fab")
		)
		(fp_line
			(start 0.12065 -0.3048)
			(end 0.67945 -0.3048)
			(stroke
				(width 0.1)
				(type default)
			)
			(layer "F.Fab")
		)
		(fp_line
			(start 0.12065 -0.2794)
			(end 0.12065 -0.3048)
			(stroke
				(width 0.1)
				(type default)
			)
			(layer "F.Fab")
		)
		(fp_line
			(start 0.67945 -0.3048)
			(end 0.67945 0.3048)
			(stroke
				(width 0.1)
				(type default)
			)
			(layer "F.Fab")
		)
		(fp_line
			(start 0.67945 0.3048)
			(end 0.120396 0.3048)
			(stroke
				(width 0.1)
				(type default)
			)
			(layer "F.Fab")
		)
		(pad "1" smd circle
			(at -0.40005 0)
			(size 0 0)
			(layers "F.Cu" "F.Mask" "F.Paste")
			(net "PVCCIN_CPU0_ATSEN")
		)
		(pad "2" smd circle
			(at 0.40005 0)
			(size 0 0)
			(layers "F.Cu" "F.Mask" "F.Paste")
			(net "GND")
		)
	)
	(footprint ""
		(layer "F.Cu")
		(at 10.339832 -160.50006)
		(property "Reference" "H128"
			(at -6.202172 -5.15239 0)
			(unlocked yes)
			(layer "F.SilkS")
			(effects
				(font
					(size 0.7874 0.5842)
					(thickness 0.1524)
				)
				(justify left)
			)
		)
		(property "Value" ""
			(at 0 0 0)
			(layer "F.Fab")
			(effects
				(font
					(size 1.27 1.27)
				)
			)
		)
		(duplicate_pad_numbers_are_jumpers no)
		(pad "1" thru_hole circle
			(at 0 0)
			(size 10.0076 10.0076)
			(drill 5.6134)
			(layers "*.Cu" "*.Mask")
			(remove_unused_layers no)
			(net "GND")
			(clearance -1.9431)
		)
	)
)
